# BASEBOARD_FAB2 (Tioga Pass) — schematic netlist excerpt (pin names and nets, part order shuffled) for the footprints in the layout excerpt that follows; sources: Cadence DE-HDL packaged netlist, KiCad conversion of Wiwynn_Tioga_Pass_MB.brd

J6L1  SCONN288_H44441003  SCONN  pkg PIP  page 54
  \12v\(1)  = P12V_NVDIMM_DEF
  VSS(93)  = GND
  DQ(4)  = M_F_DQ<4>
  VSS(92)  = GND
  DQ(0)  = M_F_DQ<0>
  VSS(91)  = GND
  DQS9P  = M_F_DQS_DP<9>
  DQS9N  = M_F_DQS_DN<9>
  VSS(90)  = GND
  DQ(6)  = M_F_DQ<6>
  VSS(89)  = GND
  DQ(2)  = M_F_DQ<2>
  VSS(88)  = GND
  DQ(12)  = M_F_DQ<12>
  VSS(87)  = GND
  DQ(8)  = M_F_DQ<8>
  VSS(86)  = GND
  DQS10P  = M_F_DQS_DP<10>
  DQS10N  = M_F_DQS_DN<10>
  VSS(85)  = GND
  DQ(14)  = M_F_DQ<14>
  VSS(84)  = GND
  DQ(10)  = M_F_DQ<10>
  VSS(83)  = GND
  DQ(20)  = M_F_DQ<20>
  VSS(82)  = GND
  DQ(16)  = M_F_DQ<16>
  VSS(81)  = GND
  DQS11P  = M_F_DQS_DP<11>
  DQS11N  = M_F_DQS_DN<11>
  VSS(80)  = GND
  DQ(22)  = M_F_DQ<22>
  VSS(79)  = GND
  DQ(18)  = M_F_DQ<18>
  VSS(78)  = GND
  DQ(28)  = M_F_DQ<28>
  VSS(77)  = GND
  DQ(24)  = M_F_DQ<24>
  VSS(76)  = GND
  DQS12P  = M_F_DQS_DP<12>
  DQS12N  = M_F_DQS_DN<12>
  VSS(75)  = GND
  DQ(30)  = M_F_DQ<30>
  VSS(74)  = GND
  DQ(26)  = M_F_DQ<26>
  VSS(73)  = GND
  CB(4)  = M_F_ECC<4>
  VSS(72)  = GND
  CB(0)  = M_F_ECC<0>
  VSS(71)  = GND
  DQS17P  = M_F_DQS_DP<17>
  DQS17N  = M_F_DQS_DN<17>
  VSS(70)  = GND
  CB(6)  = M_F_ECC<6>
  VSS(69)  = GND
  CB(2)  = M_F_ECC<2>
  VSS(68)  = GND
  RESET_N  = M_DEF_RST_N
  VDD(25)  = PVDDQ_DEF
  CKE(0)  = M_F_CKE<2>
  VDD(24)  = PVDDQ_DEF
  ACT_N  = M_F_ACT_N
  BG(0)  = M_F_BG<0>
  VDD(23)  = PVDDQ_DEF
  A12  = M_F_MA<12>
  A9  = M_F_MA<9>
  VDD(22)  = PVDDQ_DEF
  A8  = M_F_MA<8>
  A6  = M_F_MA<6>
  VDD(21)  = PVDDQ_DEF
  A3  = M_F_MA<3>
  A1  = M_F_MA<1>
  VDD(20)  = PVDDQ_DEF
  CK0P  = M_F_CLK_DP<2>
  CK0N  = M_F_CLK_DN<2>
  VDD(19)  = PVDDQ_DEF
  VTT(1)  = PVTT_DEF
  EVENT_N  = FM_DIMM_EVENT_COD_N
  A0  = M_F_MA<0>
  VDD(18)  = PVDDQ_DEF
  BA(0)  = M_F_BA<0>
  A16_RAS_N  = M_F_MA<16>
  VDD(17)  = PVDDQ_DEF
  S0_N  = M_F_CS_N<4>
  VDD(16)  = PVDDQ_DEF
  A15_CAS_N  = M_F_MA<15>
  ODT(0)  = M_F_ODT<2>
  VDD(15)  = PVDDQ_DEF
  S1_N  = M_F_CS_N<5>
  VDD(14)  = PVDDQ_DEF
  ODT(1)  = M_F_ODT<3>
  VDD(13)  = PVDDQ_DEF
  S2_N_C(0)  = M_F_CS_N<6>
  VSS(67)  = GND
  DQ(36)  = M_F_DQ<36>
  VSS(66)  = GND
  DQ(32)  = M_F_DQ<32>
  VSS(65)  = GND
  DQS13P  = M_F_DQS_DP<13>
  DQS13N  = M_F_DQS_DN<13>
  VSS(64)  = GND
  DQ(38)  = M_F_DQ<38>
  VSS(63)  = GND
  DQ(34)  = M_F_DQ<34>
  VSS(62)  = GND
  DQ(44)  = M_F_DQ<44>
  VSS(61)  = GND
  DQ(40)  = M_F_DQ<40>
  VSS(60)  = GND
  DQS14P  = M_F_DQS_DP<14>
  DQS14N  = M_F_DQS_DN<14>
  VSS(59)  = GND
  DQ(46)  = M_F_DQ<46>
  VSS(58)  = GND
  DQ(42)  = M_F_DQ<42>
  VSS(57)  = GND
  DQ(52)  = M_F_DQ<52>
  VSS(56)  = GND
  DQ(48)  = M_F_DQ<48>
  VSS(55)  = GND
  DQS15P  = M_F_DQS_DP<15>
  DQS15N  = M_F_DQS_DN<15>
  VSS(54)  = GND
  DQ(54)  = M_F_DQ<54>
  VSS(53)  = GND
  DQ(50)  = M_F_DQ<50>
  VSS(52)  = GND
  DQ(60)  = M_F_DQ<60>
  VSS(51)  = GND
  DQ(56)  = M_F_DQ<56>
  VSS(50)  = GND
  DQS16P  = M_F_DQS_DP<16>
  DQS16N  = M_F_DQS_DN<16>
  VSS(49)  = GND
  DQ(62)  = M_F_DQ<62>
  VSS(48)  = GND
  DQ(58)  = M_F_DQ<58>
  VSS(47)  = GND
  SA(0)  = PVPP_DEF
  SA(1)  = GND
  SCL  = SMB_DDR_DEF_VPP_SCL
  VPP(4)  = PVPP_DEF
  VPP(3)  = PVPP_DEF
  RFU(2)  = TP_CH_F_DIMM_F1_RFU_2
  \12v\(0)  = P12V_NVDIMM_DEF
  VREFCA  = M_F_VREF
  VSS(46)  = GND
  DQ(5)  = M_F_DQ<5>
  VSS(45)  = GND
  DQ(1)  = M_F_DQ<1>
  VSS(44)  = GND
  DQS0N  = M_F_DQS_DN<0>
  DQS0P  = M_F_DQS_DP<0>
  VSS(43)  = GND
  DQ(7)  = M_F_DQ<7>
  VSS(42)  = GND
  DQ(3)  = M_F_DQ<3>
  VSS(41)  = GND
  DQ(13)  = M_F_DQ<13>
  VSS(40)  = GND
  DQ(9)  = M_F_DQ<9>
  VSS(39)  = GND
  DQS1N  = M_F_DQS_DN<1>
  DQS1P  = M_F_DQS_DP<1>
  VSS(38)  = GND
  DQ(15)  = M_F_DQ<15>
  VSS(37)  = GND
  DQ(11)  = M_F_DQ<11>
  VSS(36)  = GND
  DQ(21)  = M_F_DQ<21>
  VSS(35)  = GND
  DQ(17)  = M_F_DQ<17>
  VSS(34)  = GND
  DQS2N  = M_F_DQS_DN<2>
  DQS2P  = M_F_DQS_DP<2>
  VSS(33)  = GND
  DQ(23)  = M_F_DQ<23>
  VSS(32)  = GND
  DQ(19)  = M_F_DQ<19>
  VSS(31)  = GND
  DQ(29)  = M_F_DQ<29>
  VSS(30)  = GND
  DQ(25)  = M_F_DQ<25>
  VSS(29)  = GND
  DQS3N  = M_F_DQS_DN<3>
  DQS3P  = M_F_DQS_DP<3>
  VSS(28)  = GND
  DQ(31)  = M_F_DQ<31>
  VSS(27)  = GND
  DQ(27)  = M_F_DQ<27>
  VSS(26)  = GND
  CB(5)  = M_F_ECC<5>
  VSS(25)  = GND
  CB(1)  = M_F_ECC<1>
  VSS(24)  = GND
  DQS8N  = M_F_DQS_DN<8>
  DQS8P  = M_F_DQS_DP<8>
  VSS(23)  = GND
  CB(7)  = M_F_ECC<7>
  VSS(22)  = GND
  CB(3)  = M_F_ECC<3>
  VSS(21)  = GND
  CKE(1)  = M_F_CKE<3>
  VDD(12)  = PVDDQ_DEF
  RFU(0)  = TP_CH_F_DIMM_F1_RFU_0
  VDD(11)  = PVDDQ_DEF
  BG(1)  = M_F_BG<1>
  ALERT_N  = M_F_ALERT_N
  VDD(10)  = PVDDQ_DEF
  A11  = M_F_MA<11>
  A7  = M_F_MA<7>
  VDD(9)  = PVDDQ_DEF
  A5  = M_F_MA<5>
  A4  = M_F_MA<4>
  VDD(8)  = PVDDQ_DEF
  A2  = M_F_MA<2>
  VDD(7)  = PVDDQ_DEF
  CK1P  = M_F_CLK_DP<3>
  CK1N  = M_F_CLK_DN<3>
  VDD(6)  = PVDDQ_DEF
  VTT(0)  = PVTT_DEF
  PAR  = M_F_PAR
  VDD(5)  = PVDDQ_DEF
  BA(1)  = M_F_BA<1>
  A10  = M_F_MA<10>
  VDD(4)  = PVDDQ_DEF
  RFU(1)  = TP_CH_F_DIMM_F1_RFU_1
  A14_WE_N  = M_F_MA<14>
  VDD(3)  = PVDDQ_DEF
  SAVE_N_NC  = FM_ADR_COMPLETE_DEF_N
  VDD(2)  = PVDDQ_DEF
  A13  = M_F_MA<13>
  VDD(1)  = PVDDQ_DEF
  A17  = M_F_MA<17>
  C(2)  = M_F_C<2>
  VDD(0)  = PVDDQ_DEF
  S3_N_C(1)  = M_F_CS_N<7>
  SA(2)  = PVPP_DEF
  VSS(20)  = GND
  DQ(37)  = M_F_DQ<37>
  VSS(19)  = GND
  DQ(33)  = M_F_DQ<33>
  VSS(18)  = GND
  DQS4N  = M_F_DQS_DN<4>
  DQS4P  = M_F_DQS_DP<4>
  VSS(17)  = GND
  DQ(39)  = M_F_DQ<39>
  VSS(16)  = GND
  DQ(35)  = M_F_DQ<35>
  VSS(15)  = GND
  DQ(45)  = M_F_DQ<45>
  VSS(14)  = GND
  DQ(41)  = M_F_DQ<41>
  VSS(13)  = GND
  DQS5N  = M_F_DQS_DN<5>
  DQS5P  = M_F_DQS_DP<5>
  VSS(12)  = GND
  DQ(47)  = M_F_DQ<47>
  VSS(11)  = GND
  DQ(43)  = M_F_DQ<43>
  VSS(10)  = GND
  DQ(53)  = M_F_DQ<53>
  VSS(9)  = GND
  DQ(49)  = M_F_DQ<49>
  VSS(8)  = GND
  DQS6N  = M_F_DQS_DN<6>
  DQS6P  = M_F_DQS_DP<6>
  VSS(7)  = GND
  DQ(55)  = M_F_DQ<55>
  VSS(6)  = GND
  DQ(51)  = M_F_DQ<51>
  VSS(5)  = GND
  DQ(61)  = M_F_DQ<61>
  VSS(4)  = GND
  DQ(57)  = M_F_DQ<57>
  VSS(3)  = GND
  DQS7N  = M_F_DQS_DN<7>
  DQS7P  = M_F_DQS_DP<7>
  VSS(2)  = GND
  DQ(63)  = M_F_DQ<63>
  VSS(1)  = GND
  DQ(59)  = M_F_DQ<59>
  VSS(0)  = GND
  VDDSPD  = PVPP_DEF
  SDA  = SMB_DDR_DEF_VPP_SDA
  VPP(1)  = PVPP_DEF
  VPP(0)  = PVPP_DEF
  VPP(2)  = PVPP_DEF

(kicad_pcb
	(version 20260206)
	(generator "pcbnew")
	(generator_version "10.0")
	(general
		(thickness 1.6)
		(legacy_teardrops no)
	)
	(paper "A4")
	(title_block
		(title "Wiwynn_Tioga_Pass_MB.brd")
		(comment 1 "Tioga Pass / footprint 4129 of 4770 (J6L1), pads 1-50 of 291")
	)
	(layers
		(0 "F.Cu" signal "TOP")
		(4 "In1.Cu" signal "L2GND")
		(6 "In2.Cu" signal "L3")
		(8 "In3.Cu" signal "L4GND")
		(10 "In4.Cu" signal "L5")
		(12 "In5.Cu" signal "L6GND")
		(14 "In6.Cu" signal "L7VCC")
		(16 "In7.Cu" signal "L8VCC")
		(18 "In8.Cu" signal "L9GND")
		(20 "In9.Cu" signal "L10")
		(22 "In10.Cu" signal "L11GND")
		(24 "In11.Cu" signal "L12")
		(26 "In12.Cu" signal "L13GND")
		(2 "B.Cu" signal "BOTTOM")
		(9 "F.Adhes" user "F.Adhesive")
		(11 "B.Adhes" user "B.Adhesive")
		(13 "F.Paste" user "Package Geometry/Pastemask Top")
		(15 "B.Paste" user "Package Geometry/Pastemask Bottom")
		(5 "F.SilkS" user "Ref Des/Silkscreen Top")
		(7 "B.SilkS" user "Ref Des/Silkscreen Bottom")
		(1 "F.Mask" user "Board Geometry/Soldermask Top")
		(3 "B.Mask" user "Board Geometry/Soldermask Bottom")
		(17 "Dwgs.User" user "User.Drawings")
		(19 "Cmts.User" user "User.Comments")
		(21 "Eco1.User" user "User.Eco1")
		(23 "Eco2.User" user "User.Eco2")
		(25 "Edge.Cuts" user "Board Geometry/Outline")
		(27 "Margin" user)
		(31 "F.CrtYd" user "Package Geometry/Place Bound Top")
		(29 "B.CrtYd" user "Package Geometry/Place Bound Bottom")
		(35 "F.Fab" user "Ref Des/Assembly Top")
		(33 "B.Fab" user "Ref Des/Assembly Bottom")
	)
	(footprint ""
		(layer "B.Cu")
		(at 194.700398 -152.078436 90)
		(property "Reference" "J6L1"
			(at 2.200148 37.96411 0)
			(unlocked yes)
			(layer "B.SilkS")
			(effects
				(font
					(size 0.7874 0.5842)
					(thickness 0.1524)
				)
				(justify left mirror)
			)
		)
		(property "Value" ""
			(at 0 0 90)
			(layer "B.Fab")
			(effects
				(font
					(size 1.27 1.27)
				)
				(justify mirror)
			)
		)
		(duplicate_pad_numbers_are_jumpers no)
		(pad "" thru_hole circle
			(at -2.29997 -5.649976 270)
			(size 2.8194 2.8194)
			(drill 2.4384)
			(layers "*.Cu" "*.Mask")
			(remove_unused_layers no)
			(clearance 0.127)
			(thermal_gap 0.127)
		)
		(pad "" thru_hole oval
			(at -2.29997 68.90004 270)
			(size 2.8194 1.5748)
			(drill oval 2.4384 1.1938)
			(layers "*.Cu" "*.Mask")
			(remove_unused_layers no)
			(clearance 0.127)
			(thermal_gap 0.127)
		)
		(pad "" thru_hole circle
			(at -2.29997 132.299964 270)
			(size 2.8194 2.8194)
			(drill 2.4384)
			(layers "*.Cu" "*.Mask")
			(remove_unused_layers no)
			(clearance 0.127)
			(thermal_gap 0.127)
		)
		(pad "1" smd rect
			(at 0 0 270)
			(size 1.8034 0.508)
			(layers "B.Cu" "B.Mask" "B.Paste")
			(net "P12V_NVDIMM_DEF")
		)
		(pad "2" smd rect
			(at 0 0.849884 270)
			(size 1.8034 0.508)
			(layers "B.Cu" "B.Mask" "B.Paste")
			(net "GND")
		)
		(pad "3" smd rect
			(at 0 1.700022 270)
			(size 1.8034 0.508)
			(layers "B.Cu" "B.Mask" "B.Paste")
			(net "M_F_DQ<4>")
		)
		(pad "4" smd rect
			(at 0 2.549906 270)
			(size 1.8034 0.508)
			(layers "B.Cu" "B.Mask" "B.Paste")
			(net "GND")
		)
		(pad "5" smd rect
			(at 0 3.400044 270)
			(size 1.8034 0.508)
			(layers "B.Cu" "B.Mask" "B.Paste")
			(net "M_F_DQ<0>")
		)
		(pad "6" smd rect
			(at 0 4.249928 270)
			(size 1.8034 0.508)
			(layers "B.Cu" "B.Mask" "B.Paste")
			(net "GND")
		)
		(pad "7" smd rect
			(at 0 5.100066 270)
			(size 1.8034 0.508)
			(layers "B.Cu" "B.Mask" "B.Paste")
			(net "M_F_DQS_DP<9>")
		)
		(pad "8" smd rect
			(at 0 5.94995 270)
			(size 1.8034 0.508)
			(layers "B.Cu" "B.Mask" "B.Paste")
			(net "M_F_DQS_DN<9>")
		)
		(pad "9" smd rect
			(at 0 6.800088 270)
			(size 1.8034 0.508)
			(layers "B.Cu" "B.Mask" "B.Paste")
			(net "GND")
		)
		(pad "10" smd rect
			(at 0 7.649972 270)
			(size 1.8034 0.508)
			(layers "B.Cu" "B.Mask" "B.Paste")
			(net "M_F_DQ<6>")
		)
		(pad "11" smd rect
			(at 0 8.50011 270)
			(size 1.8034 0.508)
			(layers "B.Cu" "B.Mask" "B.Paste")
			(net "GND")
		)
		(pad "12" smd rect
			(at 0 9.349994 270)
			(size 1.8034 0.508)
			(layers "B.Cu" "B.Mask" "B.Paste")
			(net "M_F_DQ<2>")
		)
		(pad "13" smd rect
			(at 0 10.199878 270)
			(size 1.8034 0.508)
			(layers "B.Cu" "B.Mask" "B.Paste")
			(net "GND")
		)
		(pad "14" smd rect
			(at 0 11.050016 270)
			(size 1.8034 0.508)
			(layers "B.Cu" "B.Mask" "B.Paste")
			(net "M_F_DQ<12>")
		)
		(pad "15" smd rect
			(at 0 11.8999 270)
			(size 1.8034 0.508)
			(layers "B.Cu" "B.Mask" "B.Paste")
			(net "GND")
		)
		(pad "16" smd rect
			(at 0 12.750038 270)
			(size 1.8034 0.508)
			(layers "B.Cu" "B.Mask" "B.Paste")
			(net "M_F_DQ<8>")
		)
		(pad "17" smd rect
			(at 0 13.599922 270)
			(size 1.8034 0.508)
			(layers "B.Cu" "B.Mask" "B.Paste")
			(net "GND")
		)
		(pad "18" smd rect
			(at 0 14.45006 270)
			(size 1.8034 0.508)
			(layers "B.Cu" "B.Mask" "B.Paste")
			(net "M_F_DQS_DP<10>")
		)
		(pad "19" smd rect
			(at 0 15.299944 270)
			(size 1.8034 0.508)
			(layers "B.Cu" "B.Mask" "B.Paste")
			(net "M_F_DQS_DN<10>")
		)
		(pad "20" smd rect
			(at 0 16.150082 270)
			(size 1.8034 0.508)
			(layers "B.Cu" "B.Mask" "B.Paste")
			(net "GND")
		)
		(pad "21" smd rect
			(at 0 16.999966 270)
			(size 1.8034 0.508)
			(layers "B.Cu" "B.Mask" "B.Paste")
			(net "M_F_DQ<14>")
		)
		(pad "22" smd rect
			(at 0 17.850104 270)
			(size 1.8034 0.508)
			(layers "B.Cu" "B.Mask" "B.Paste")
			(net "GND")
		)
		(pad "23" smd rect
			(at 0 18.699988 270)
			(size 1.8034 0.508)
			(layers "B.Cu" "B.Mask" "B.Paste")
			(net "M_F_DQ<10>")
		)
		(pad "24" smd rect
			(at 0 19.550126 270)
			(size 1.8034 0.508)
			(layers "B.Cu" "B.Mask" "B.Paste")
			(net "GND")
		)
		(pad "25" smd rect
			(at 0 20.40001 270)
			(size 1.8034 0.508)
			(layers "B.Cu" "B.Mask" "B.Paste")
			(net "M_F_DQ<20>")
		)
		(pad "26" smd rect
			(at 0 21.249894 270)
			(size 1.8034 0.508)
			(layers "B.Cu" "B.Mask" "B.Paste")
			(net "GND")
		)
		(pad "27" smd rect
			(at 0 22.100032 270)
			(size 1.8034 0.508)
			(layers "B.Cu" "B.Mask" "B.Paste")
			(net "M_F_DQ<16>")
		)
		(pad "28" smd rect
			(at 0 22.949916 270)
			(size 1.8034 0.508)
			(layers "B.Cu" "B.Mask" "B.Paste")
			(net "GND")
		)
		(pad "29" smd rect
			(at 0 23.800054 270)
			(size 1.8034 0.508)
			(layers "B.Cu" "B.Mask" "B.Paste")
			(net "M_F_DQS_DP<11>")
		)
		(pad "30" smd rect
			(at 0 24.649938 270)
			(size 1.8034 0.508)
			(layers "B.Cu" "B.Mask" "B.Paste")
			(net "M_F_DQS_DN<11>")
		)
		(pad "31" smd rect
			(at 0 25.500076 270)
			(size 1.8034 0.508)
			(layers "B.Cu" "B.Mask" "B.Paste")
			(net "GND")
		)
		(pad "32" smd rect
			(at 0 26.34996 270)
			(size 1.8034 0.508)
			(layers "B.Cu" "B.Mask" "B.Paste")
			(net "M_F_DQ<22>")
		)
		(pad "33" smd rect
			(at 0 27.200098 270)
			(size 1.8034 0.508)
			(layers "B.Cu" "B.Mask" "B.Paste")
			(net "GND")
		)
		(pad "34" smd rect
			(at 0 28.049982 270)
			(size 1.8034 0.508)
			(layers "B.Cu" "B.Mask" "B.Paste")
			(net "M_F_DQ<18>")
		)
		(pad "35" smd rect
			(at 0 28.90012 270)
			(size 1.8034 0.508)
			(layers "B.Cu" "B.Mask" "B.Paste")
			(net "GND")
		)
		(pad "36" smd rect
			(at 0 29.750004 270)
			(size 1.8034 0.508)
			(layers "B.Cu" "B.Mask" "B.Paste")
			(net "M_F_DQ<28>")
		)
		(pad "37" smd rect
			(at 0 30.599888 270)
			(size 1.8034 0.508)
			(layers "B.Cu" "B.Mask" "B.Paste")
			(net "GND")
		)
		(pad "38" smd rect
			(at 0 31.450026 270)
			(size 1.8034 0.508)
			(layers "B.Cu" "B.Mask" "B.Paste")
			(net "M_F_DQ<24>")
		)
		(pad "39" smd rect
			(at 0 32.29991 270)
			(size 1.8034 0.508)
			(layers "B.Cu" "B.Mask" "B.Paste")
			(net "GND")
		)
		(pad "40" smd rect
			(at 0 33.150048 270)
			(size 1.8034 0.508)
			(layers "B.Cu" "B.Mask" "B.Paste")
			(net "M_F_DQS_DP<12>")
		)
		(pad "41" smd rect
			(at 0 33.999932 270)
			(size 1.8034 0.508)
			(layers "B.Cu" "B.Mask" "B.Paste")
			(net "M_F_DQS_DN<12>")
		)
		(pad "42" smd rect
			(at 0 34.85007 270)
			(size 1.8034 0.508)
			(layers "B.Cu" "B.Mask" "B.Paste")
			(net "GND")
		)
		(pad "43" smd rect
			(at 0 35.699954 270)
			(size 1.8034 0.508)
			(layers "B.Cu" "B.Mask" "B.Paste")
			(net "M_F_DQ<30>")
		)
		(pad "44" smd rect
			(at 0 36.550092 270)
			(size 1.8034 0.508)
			(layers "B.Cu" "B.Mask" "B.Paste")
			(net "GND")
		)
		(pad "45" smd rect
			(at 0 37.399976 270)
			(size 1.8034 0.508)
			(layers "B.Cu" "B.Mask" "B.Paste")
			(net "M_F_DQ<26>")
		)
		(pad "46" smd rect
			(at 0 38.250114 270)
			(size 1.8034 0.508)
			(layers "B.Cu" "B.Mask" "B.Paste")
			(net "GND")
		)
		(pad "47" smd rect
			(at 0 39.099998 270)
			(size 1.8034 0.508)
			(layers "B.Cu" "B.Mask" "B.Paste")
			(net "M_F_ECC<4>")
		)
	)
)
